(kicad_pcb
	(version 20260206)
	(generator "pcbnew")
	(generator_version "10.0")
	(general
		(thickness 1.6)
		(legacy_teardrops no)
	)
	(paper "A4")
	(title_block
		(title "v1-chassis-manager — T6M_CM_d_v01_1031_1645.brd")
		(comment 1 "Open CloudServer (Microsoft) / footprints 781-788 of 2512")
	)
	(layers
		(0 "F.Cu" signal "TOP")
		(4 "In1.Cu" signal "GND1")
		(6 "In2.Cu" signal "IN1")
		(8 "In3.Cu" signal "VCC1")
		(10 "In4.Cu" signal "VCC2")
		(12 "In5.Cu" signal "GND2")
		(14 "In6.Cu" signal "IN2")
		(16 "In7.Cu" signal "IN3")
		(18 "In8.Cu" signal "GND3")
		(2 "B.Cu" signal "BOTTOM")
		(9 "F.Adhes" user "F.Adhesive")
		(11 "B.Adhes" user "B.Adhesive")
		(13 "F.Paste" user "Package Geometry/Pastemask Top")
		(15 "B.Paste" user "Package Geometry/Pastemask Bottom")
		(5 "F.SilkS" user "Ref Des/Silkscreen Top")
		(7 "B.SilkS" user "Ref Des/Silkscreen Bottom")
		(1 "F.Mask" user "Board Geometry/Soldermask Top")
		(3 "B.Mask" user "Board Geometry/Soldermask Bottom")
		(17 "Dwgs.User" user "User.Drawings")
		(19 "Cmts.User" user "User.Comments")
		(21 "Eco1.User" user "User.Eco1")
		(23 "Eco2.User" user "User.Eco2")
		(25 "Edge.Cuts" user "Board Geometry/Outline")
		(27 "Margin" user)
		(31 "F.CrtYd" user "Package Geometry/Place Bound Top")
		(29 "B.CrtYd" user "Package Geometry/Place Bound Bottom")
		(35 "F.Fab" user "Ref Des/Assembly Top")
		(33 "B.Fab" user "Ref Des/Assembly Bottom")
	)
	(footprint ""
		(layer "F.Cu")
		(at 63.177166 -96.709992 90)
		(property "Reference" "R104"
			(at -54.98719 28.497276 90)
			(unlocked yes)
			(layer "F.SilkS")
			(effects
				(font
					(size 0.7874 0.5842)
					(thickness 0.1524)
				)
				(justify left)
			)
		)
		(property "Value" ""
			(at 0 0 90)
			(layer "F.Fab")
			(effects
				(font
					(size 1.27 1.27)
				)
			)
		)
		(duplicate_pad_numbers_are_jumpers no)
		(fp_line
			(start 0.7874 -0.4064)
			(end 0.7874 0.4064)
			(stroke
				(width 0.1524)
				(type default)
			)
			(layer "F.SilkS")
		)
		(fp_line
			(start -0.7874 -0.4064)
			(end 0.7874 -0.4064)
			(stroke
				(width 0.1524)
				(type default)
			)
			(layer "F.SilkS")
		)
		(fp_line
			(start 0.7874 0.4064)
			(end -0.7874 0.4064)
			(stroke
				(width 0.1524)
				(type default)
			)
			(layer "F.SilkS")
		)
		(fp_line
			(start -0.7874 0.4064)
			(end -0.7874 -0.4064)
			(stroke
				(width 0.1524)
				(type default)
			)
			(layer "F.SilkS")
		)
		(fp_poly
			(pts
				(xy -0.508 0.2794) (xy -0.508 0.2286) (xy -0.635 0.2286) (xy -0.635 -0.254) (xy -0.5334 -0.254)
				(xy -0.5334 -0.2794) (xy 0.5334 -0.2794) (xy 0.5334 -0.254) (xy 0.635 -0.254) (xy 0.635 0.254) (xy 0.5334 0.254)
				(xy 0.5334 0.2794)
			)
			(stroke
				(width 0)
				(type default)
			)
			(fill no)
			(layer "F.CrtYd")
		)
		(pad "1" smd rect
			(at 0.40005 0 90)
			(size 0.4572 0.508)
			(layers "F.Cu" "F.Mask" "F.Paste")
			(net "GND")
		)
		(pad "2" smd rect
			(at -0.40005 0 90)
			(size 0.4572 0.508)
			(layers "F.Cu" "F.Mask" "F.Paste")
			(net "A_CPU_NODE1_NTB_CROSSLK_MODE")
		)
	)
	(footprint ""
		(layer "F.Cu")
		(at 137.65276 -188.126624 90)
		(property "Reference" "C645"
			(at 5.519674 -0.070612 90)
			(unlocked yes)
			(layer "F.SilkS")
			(effects
				(font
					(size 0.7874 0.5842)
					(thickness 0.1524)
				)
				(justify left)
			)
		)
		(property "Value" ""
			(at 0 0 90)
			(layer "F.Fab")
			(effects
				(font
					(size 1.27 1.27)
				)
			)
		)
		(duplicate_pad_numbers_are_jumpers no)
		(fp_line
			(start 0.7874 -0.4064)
			(end 0.7874 0.4064)
			(stroke
				(width 0.1524)
				(type default)
			)
			(layer "F.SilkS")
		)
		(fp_line
			(start -0.7874 -0.4064)
			(end 0.7874 -0.4064)
			(stroke
				(width 0.1524)
				(type default)
			)
			(layer "F.SilkS")
		)
		(fp_line
			(start 0 0.381)
			(end 0 -0.381)
			(stroke
				(width 0.1524)
				(type default)
			)
			(layer "F.SilkS")
		)
		(fp_line
			(start 0.7874 0.4064)
			(end -0.7874 0.4064)
			(stroke
				(width 0.1524)
				(type default)
			)
			(layer "F.SilkS")
		)
		(fp_line
			(start -0.7874 0.4064)
			(end -0.7874 -0.4064)
			(stroke
				(width 0.1524)
				(type default)
			)
			(layer "F.SilkS")
		)
		(fp_poly
			(pts
				(xy -0.5334 0.254) (xy -0.635 0.254) (xy -0.635 0.2286) (xy -0.635 -0.254) (xy -0.5334 -0.254) (xy -0.5334 -0.2794)
				(xy 0.5334 -0.2794) (xy 0.5334 -0.254) (xy 0.635 -0.254) (xy 0.635 0.254) (xy 0.5334 0.254) (xy 0.5334 0.2794)
				(xy -0.508 0.2794) (xy -0.5334 0.2794)
			)
			(stroke
				(width 0)
				(type default)
			)
			(fill no)
			(layer "F.CrtYd")
		)
		(pad "1" smd rect
			(at 0.40005 0 90)
			(size 0.4572 0.508)
			(layers "F.Cu" "F.Mask" "F.Paste")
			(net "T10_NODE4_EN_R")
		)
		(pad "2" smd rect
			(at -0.40005 0 90)
			(size 0.4572 0.508)
			(layers "F.Cu" "F.Mask" "F.Paste")
			(net "GND")
		)
	)
	(footprint ""
		(layer "F.Cu")
		(at 95.113094 -139.085066 180)
		(property "Reference" "R1085"
			(at 1.865122 4.096766 0)
			(unlocked yes)
			(layer "F.SilkS")
			(effects
				(font
					(size 0.7874 0.5842)
					(thickness 0.1524)
				)
				(justify left)
			)
		)
		(property "Value" ""
			(at 0 0 180)
			(layer "F.Fab")
			(effects
				(font
					(size 1.27 1.27)
				)
			)
		)
		(duplicate_pad_numbers_are_jumpers no)
		(fp_line
			(start 0.7874 0.4064)
			(end -0.7874 0.4064)
			(stroke
				(width 0.1524)
				(type default)
			)
			(layer "F.SilkS")
		)
		(fp_line
			(start 0.7874 -0.4064)
			(end 0.7874 0.4064)
			(stroke
				(width 0.1524)
				(type default)
			)
			(layer "F.SilkS")
		)
		(fp_line
			(start -0.7874 0.4064)
			(end -0.7874 -0.4064)
			(stroke
				(width 0.1524)
				(type default)
			)
			(layer "F.SilkS")
		)
		(fp_line
			(start -0.7874 -0.4064)
			(end 0.7874 -0.4064)
			(stroke
				(width 0.1524)
				(type default)
			)
			(layer "F.SilkS")
		)
		(fp_poly
			(pts
				(xy -0.508 0.2794) (xy -0.508 0.2286) (xy -0.635 0.2286) (xy -0.635 -0.254) (xy -0.5334 -0.254)
				(xy -0.5334 -0.2794) (xy 0.5334 -0.2794) (xy 0.5334 -0.254) (xy 0.635 -0.254) (xy 0.635 0.254) (xy 0.5334 0.254)
				(xy 0.5334 0.2794)
			)
			(stroke
				(width 0)
				(type default)
			)
			(fill no)
			(layer "F.CrtYd")
		)
		(pad "1" smd rect
			(at 0.40005 0 180)
			(size 0.4572 0.508)
			(layers "F.Cu" "F.Mask" "F.Paste")
			(net "P1V05_SUS_NODE1_ADJ")
		)
		(pad "2" smd rect
			(at -0.40005 0 180)
			(size 0.4572 0.508)
			(layers "F.Cu" "F.Mask" "F.Paste")
			(net "P1V05_SUS_NODE1_ADJ_S")
		)
	)
	(footprint ""
		(layer "F.Cu")
		(at 31.655512 -185.390536 -90)
		(property "Reference" "C780"
			(at -4.83616 4.312412 90)
			(unlocked yes)
			(layer "F.SilkS")
			(effects
				(font
					(size 0.7874 0.5842)
					(thickness 0.1524)
				)
			)
		)
		(property "Value" ""
			(at 0 0 270)
			(layer "F.Fab")
			(effects
				(font
					(size 1.27 1.27)
				)
			)
		)
		(duplicate_pad_numbers_are_jumpers no)
		(fp_line
			(start -1.2954 0.5842)
			(end -1.2954 -0.5842)
			(stroke
				(width 0.1524)
				(type default)
			)
			(layer "F.SilkS")
		)
		(fp_line
			(start 1.2954 0.5842)
			(end -1.2954 0.5842)
			(stroke
				(width 0.1524)
				(type default)
			)
			(layer "F.SilkS")
		)
		(fp_line
			(start -1.2954 -0.5842)
			(end 1.2954 -0.5842)
			(stroke
				(width 0.1524)
				(type default)
			)
			(layer "F.SilkS")
		)
		(fp_line
			(start 0 -0.5842)
			(end 0 0.5842)
			(stroke
				(width 0.1524)
				(type default)
			)
			(layer "F.SilkS")
		)
		(fp_line
			(start 1.2954 -0.5842)
			(end 1.2954 0.5842)
			(stroke
				(width 0.1524)
				(type default)
			)
			(layer "F.SilkS")
		)
		(fp_poly
			(pts
				(xy 0.8636 -0.4572) (xy 0.8636 -0.3556) (xy 1.143 -0.3556) (xy 1.143 0.3556) (xy 0.8636 0.3556)
				(xy 0.8636 0.4572) (xy -0.8636 0.4572) (xy -0.8636 0.3556) (xy -1.143 0.3556) (xy -1.143 -0.3556)
				(xy -0.8636 -0.3556) (xy -0.8636 -0.4572)
			)
			(stroke
				(width 0)
				(type default)
			)
			(fill no)
			(layer "F.CrtYd")
		)
		(fp_line
			(start -0.884936 0.504952)
			(end -0.884936 -0.504952)
			(stroke
				(width 0.1)
				(type default)
			)
			(layer "F.Fab")
		)
		(fp_line
			(start 0.884936 0.504952)
			(end -0.884936 0.504952)
			(stroke
				(width 0.1)
				(type default)
			)
			(layer "F.Fab")
		)
		(fp_line
			(start -0.884936 -0.504952)
			(end 0.884936 -0.504952)
			(stroke
				(width 0.1)
				(type default)
			)
			(layer "F.Fab")
		)
		(fp_line
			(start 0.884936 -0.504952)
			(end 0.884936 0.504952)
			(stroke
				(width 0.1)
				(type default)
			)
			(layer "F.Fab")
		)
		(pad "1" smd rect
			(at 0.7366 0)
			(size 0.7112 0.8128)
			(layers "F.Cu" "F.Mask" "F.Paste")
			(net "VR_HSC_NODE1_TIMER")
		)
		(pad "2" smd rect
			(at -0.7366 0)
			(size 0.7112 0.8128)
			(layers "F.Cu" "F.Mask" "F.Paste")
			(net "AGND_HSC_NODE1")
		)
	)
	(footprint ""
		(layer "F.Cu")
		(at 72.500998 -13.02766 180)
		(property "Reference" "PC45"
			(at -2.854198 -1.762506 0)
			(unlocked yes)
			(layer "F.SilkS")
			(effects
				(font
					(size 0.7874 0.5842)
					(thickness 0.1524)
				)
				(justify left)
			)
		)
		(property "Value" ""
			(at 0 0 180)
			(layer "F.Fab")
			(effects
				(font
					(size 1.27 1.27)
				)
			)
		)
		(duplicate_pad_numbers_are_jumpers no)
		(fp_line
			(start 2.2098 0.9398)
			(end -2.2098 0.9398)
			(stroke
				(width 0.1524)
				(type default)
			)
			(layer "F.SilkS")
		)
		(fp_line
			(start 2.2098 -0.9398)
			(end 2.2098 0.9398)
			(stroke
				(width 0.1524)
				(type default)
			)
			(layer "F.SilkS")
		)
		(fp_line
			(start 0 -0.9398)
			(end 0 0.9398)
			(stroke
				(width 0.1524)
				(type default)
			)
			(layer "F.SilkS")
		)
		(fp_line
			(start -2.2098 0.9398)
			(end -2.2098 -0.9398)
			(stroke
				(width 0.1524)
				(type default)
			)
			(layer "F.SilkS")
		)
		(fp_line
			(start -2.2098 -0.9398)
			(end 2.2098 -0.9398)
			(stroke
				(width 0.1524)
				(type default)
			)
			(layer "F.SilkS")
		)
		(fp_poly
			(pts
				(xy -1.6764 0.889) (xy -1.6764 0.7874) (xy -2.0574 0.7874) (xy -2.0574 -0.7874) (xy -1.6764 -0.7874)
				(xy -1.6764 -0.9398) (xy 1.6764 -0.9398) (xy 1.6764 -0.7874) (xy 2.0574 -0.7874) (xy 2.0574 0.7874)
				(xy 1.6764 0.7874) (xy 1.6764 0.9398) (xy -1.6764 0.9398)
			)
			(stroke
				(width 0)
				(type default)
			)
			(fill no)
			(layer "F.CrtYd")
		)
		(fp_line
			(start 1.700022 0.899922)
			(end -1.700022 0.899922)
			(stroke
				(width 0.1)
				(type default)
			)
			(layer "F.Fab")
		)
		(fp_line
			(start 1.700022 -0.899922)
			(end 1.700022 0.899922)
			(stroke
				(width 0.1)
				(type default)
			)
			(layer "F.Fab")
		)
		(fp_line
			(start -1.700022 0.899922)
			(end -1.700022 -0.899922)
			(stroke
				(width 0.1)
				(type default)
			)
			(layer "F.Fab")
		)
		(fp_line
			(start -1.700022 -0.899922)
			(end 1.700022 -0.899922)
			(stroke
				(width 0.1)
				(type default)
			)
			(layer "F.Fab")
		)
		(pad "1" smd rect
			(at 1.4732 0 180)
			(size 1.1684 1.5748)
			(layers "F.Cu" "F.Mask" "F.Paste")
			(net "P12V_AUX")
		)
		(pad "2" smd rect
			(at -1.4732 0 180)
			(size 1.1684 1.5748)
			(layers "F.Cu" "F.Mask" "F.Paste")
			(net "GND")
		)
	)
	(footprint ""
		(layer "F.Cu")
		(at 103.329994 -115.01882 180)
		(property "Reference" "PC117"
			(at 5.918454 -0.029972 0)
			(unlocked yes)
			(layer "F.SilkS")
			(effects
				(font
					(size 0.7874 0.5842)
					(thickness 0.1524)
				)
				(justify left)
			)
		)
		(property "Value" ""
			(at 0 0 180)
			(layer "F.Fab")
			(effects
				(font
					(size 1.27 1.27)
				)
			)
		)
		(duplicate_pad_numbers_are_jumpers no)
		(fp_line
			(start 1.905 0.8636)
			(end -1.905 0.8636)
			(stroke
				(width 0.1524)
				(type default)
			)
			(layer "F.SilkS")
		)
		(fp_line
			(start 1.905 -0.8636)
			(end 1.905 0.8636)
			(stroke
				(width 0.1524)
				(type default)
			)
			(layer "F.SilkS")
		)
		(fp_line
			(start 0 0.8382)
			(end 0 -0.8382)
			(stroke
				(width 0.1524)
				(type default)
			)
			(layer "F.SilkS")
		)
		(fp_line
			(start -1.905 0.8636)
			(end -1.905 -0.8636)
			(stroke
				(width 0.1524)
				(type default)
			)
			(layer "F.SilkS")
		)
		(fp_line
			(start -1.905 -0.8636)
			(end 1.905 -0.8636)
			(stroke
				(width 0.1524)
				(type default)
			)
			(layer "F.SilkS")
		)
		(fp_rect
			(start -1.524 0.7366)
			(end 1.524 -0.7366)
			(stroke
				(width 0)
				(type default)
			)
			(fill no)
			(layer "F.CrtYd")
		)
		(pad "1" smd rect
			(at 0.94996 0 180)
			(size 1.1176 1.3716)
			(layers "F.Cu" "F.Mask" "F.Paste")
			(net "GND")
		)
		(pad "2" smd rect
			(at -0.94996 0 180)
			(size 1.1176 1.3716)
			(layers "F.Cu" "F.Mask" "F.Paste")
			(net "PV_VCCP_NODE1")
		)
	)
	(footprint ""
		(layer "F.Cu")
		(at 126.22276 -185.205624 -90)
		(property "Reference" "R974"
			(at -4.675632 0.173228 90)
			(unlocked yes)
			(layer "F.SilkS")
			(effects
				(font
					(size 0.7874 0.5842)
					(thickness 0.1524)
				)
				(justify left)
			)
		)
		(property "Value" ""
			(at 0 0 270)
			(layer "F.Fab")
			(effects
				(font
					(size 1.27 1.27)
				)
			)
		)
		(duplicate_pad_numbers_are_jumpers no)
		(fp_line
			(start -0.7874 0.4064)
			(end -0.7874 -0.4064)
			(stroke
				(width 0.1524)
				(type default)
			)
			(layer "F.SilkS")
		)
		(fp_line
			(start 0.7874 0.4064)
			(end -0.7874 0.4064)
			(stroke
				(width 0.1524)
				(type default)
			)
			(layer "F.SilkS")
		)
		(fp_line
			(start -0.7874 -0.4064)
			(end 0.7874 -0.4064)
			(stroke
				(width 0.1524)
				(type default)
			)
			(layer "F.SilkS")
		)
		(fp_line
			(start 0.7874 -0.4064)
			(end 0.7874 0.4064)
			(stroke
				(width 0.1524)
				(type default)
			)
			(layer "F.SilkS")
		)
		(fp_poly
			(pts
				(xy -0.508 0.2794) (xy -0.508 0.2286) (xy -0.635 0.2286) (xy -0.635 -0.254) (xy -0.5334 -0.254)
				(xy -0.5334 -0.2794) (xy 0.5334 -0.2794) (xy 0.5334 -0.254) (xy 0.635 -0.254) (xy 0.635 0.254) (xy 0.5334 0.254)
				(xy 0.5334 0.2794)
			)
			(stroke
				(width 0)
				(type default)
			)
			(fill no)
			(layer "F.CrtYd")
		)
		(pad "1" smd rect
			(at 0.40005 0 270)
			(size 0.4572 0.508)
			(layers "F.Cu" "F.Mask" "F.Paste")
			(net "UART_T9_NODE4_RXD")
		)
		(pad "2" smd rect
			(at -0.40005 0 270)
			(size 0.4572 0.508)
			(layers "F.Cu" "F.Mask" "F.Paste")
			(net "UART_T9_NODE4_RXD_R")
		)
	)
	(footprint ""
		(layer "F.Cu")
		(at 103.1621 -129.745994 180)
		(property "Reference" "PJ16"
			(at 6.798818 -4.947158 90)
			(unlocked yes)
			(layer "F.SilkS")
			(effects
				(font
					(size 0.7874 0.5842)
					(thickness 0.1524)
				)
				(justify left)
			)
		)
		(property "Value" ""
			(at 0 0 180)
			(layer "F.Fab")
			(effects
				(font
					(size 1.27 1.27)
				)
			)
		)
		(duplicate_pad_numbers_are_jumpers no)
		(fp_poly
			(pts
				(xy 0.2794 0.907796) (xy 0.254 0.907796) (xy 0.254 1.0414) (xy -0.254 1.0414) (xy -0.254 1.034796)
				(xy -0.254 0.933196) (xy -0.2794 0.933196) (xy -0.2794 -0.133604) (xy -0.254 -0.133604) (xy -0.254 -0.235204)
				(xy 0.254 -0.235204) (xy 0.254 -0.133604) (xy 0.2794 -0.133604)
			)
			(stroke
				(width 0)
				(type default)
			)
			(fill no)
			(layer "F.CrtYd")
		)
		(pad "1" smd custom
			(at 0 -0.000254 180)
			(size 0.127 0.127)
			(layers "F.Cu" "F.Mask" "F.Paste")
			(net "FM_CPLD_NODE1_PVCCP_EN")
			(options
				(clearance outline)
				(anchor circle)
			)
			(primitives
				(gr_poly
					(pts
						(xy -0.127 0.508) (xy -0.127 -0.0508) (xy -0.254 -0.0508) (xy -0.254 -0.508) (xy 0.254 -0.508)
						(xy 0.254 -0.0508) (xy 0.127 -0.0508) (xy 0.127 0.508)
					)
					(width 0)
					(fill yes)
				)
			)
		)
		(pad "2" smd rect
			(at 0 0.799846 270)
			(size 0.4572 0.508)
			(layers "F.Cu" "F.Mask" "F.Paste")
			(net "VR_PVCCP_NODE1_EN")
		)
		(zone
			(layer "F.Cu")
			(hatch none 0.5)
			(connect_pads
				(clearance 0)
			)
			(min_thickness 0.25)
			(keepout
				(tracks allowed)
				(vias not_allowed)
				(pads allowed)
				(copperpour not_allowed)
				(footprints allowed)
			)
			(placement
				(enabled no)
				(sheetname "")
			)
			(fill
				(thermal_gap 0.5)
				(thermal_bridge_width 0.5)
				(island_removal_mode 0)
			)
			(polygon
				(pts
					(xy 103.4669 -130.83159) (xy 102.8573 -130.83159) (xy 102.8573 -129.45999) (xy 103.4669 -129.45999)
				)
			)
		)
	)
)
